Created on vSure / Trilogy - Netlist Compare Summary.

Version 

FTP Site : valor.com
WEB Site : http://www.valor.com 

DATE :  13 Nov 2014
TIME :  16:06:31


     MISMATCH SUMMARY REPORT
     -----------------------

Job  : 13948-1b_z12023026      Job  : 13948-1b_z12023026
Step : db                      Step : db
Type : CAD                     Type : CURCAD

-----------------------------------------------

 Mismatch Type: shorted

   GND                   -   NET00000            
   AGND_P0V9_C           -    "                  
   AGND_CURRENT_MON      -    "                  
   AGND_P0V9_E           -    "                  
   AGND_P1V5_E           -    "                  
   AGND_P1V8_STBY        -    "                  
   AGND_P3V3_STBY        -    "                  
   AGND_P5V_STBY         -    "                  
   P5V_STBY              -   NET00024            
   P5V_STBY_CC           -    "                  
   P3V3_STBY             -   NET00046            
   FLA_WPN               -    "                  
   ROMD0_R               -   NET00615            
   ROMD0                 -    "                  
   ROMD1_R               -   NET00621            
   ROMD1                 -    "                  
   ROMD2_R               -   NET00752            
   ROMD2                 -    "                  
   FLA_CS_R              -   NET00753            
   FLA_CS                -    "                  
   P1V5_E                -   NET00839            
   P1V5_E_CC             -    "                  

 Total : 8
-----------------------------------------------

 Mismatch Type: broken


 Total : 0
-----------------------------------------------

 Mismatch Type: missing


 Total : 0
-----------------------------------------------

 Mismatch Type: extra


 Total : 0
-----------------------------------------------
